# S9S_MB_2U (Grand Teton) — schematic netlist excerpt (pin names and nets, part order shuffled) for the footprints in the layout excerpt that follows; sources: Cadence DE-HDL packaged netlist, KiCad conversion of 03242023_DA0F0TMBIJ0_F0T_Motherboard_J_brd_V01_OCP.brd

R2950  Q_RES  4.7K 5% EMPTY  pkg 0402LF  page 245 : A = P3V3_AUX ; B = FM_PDB_BUF_EN_R
R1405  Q_RES  2K 1% CHIP  pkg 0402LF  page 219 : A = FM_PVCCIN_CPU0_R_EN ; B = GND

(kicad_pcb
	(version 20260206)
	(generator "pcbnew")
	(generator_version "10.0")
	(general
		(thickness 1.6)
		(legacy_teardrops no)
	)
	(paper "A4")
	(title_block
		(title "03242023_DA0F0TMBIJ0_F0T_Motherboard_J_brd_V01_OCP.brd")
		(comment 1 "Grand Teton / footprints 3836-3837 of 6105")
	)
	(layers
		(0 "F.Cu" signal "TOP")
		(4 "In1.Cu" signal "GND")
		(6 "In2.Cu" signal "IN1")
		(8 "In3.Cu" signal "GND1")
		(10 "In4.Cu" signal "IN2")
		(12 "In5.Cu" signal "GND2")
		(14 "In6.Cu" signal "IN3")
		(16 "In7.Cu" signal "GND3")
		(18 "In8.Cu" signal "VCC")
		(20 "In9.Cu" signal "VCC1")
		(22 "In10.Cu" signal "GND4")
		(24 "In11.Cu" signal "IN4")
		(26 "In12.Cu" signal "GND5")
		(28 "In13.Cu" signal "IN5")
		(30 "In14.Cu" signal "GND6")
		(32 "In15.Cu" signal "IN6")
		(34 "In16.Cu" signal "GND7")
		(2 "B.Cu" signal "BOTTOM")
		(9 "F.Adhes" user "F.Adhesive")
		(11 "B.Adhes" user "B.Adhesive")
		(13 "F.Paste" user "Package Geometry/Pastemask Top")
		(15 "B.Paste" user "Package Geometry/Pastemask Bottom")
		(5 "F.SilkS" user "Ref Des/Silkscreen Top")
		(7 "B.SilkS" user "Ref Des/Silkscreen Bottom")
		(1 "F.Mask" user "Board Geometry/Soldermask Top")
		(3 "B.Mask" user "Board Geometry/Soldermask Bottom")
		(17 "Dwgs.User" user "User.Drawings")
		(19 "Cmts.User" user "User.Comments")
		(21 "Eco1.User" user "User.Eco1")
		(23 "Eco2.User" user "User.Eco2")
		(25 "Edge.Cuts" user "Board Geometry/Outline")
		(27 "Margin" user)
		(31 "F.CrtYd" user "Package Geometry/Place Bound Top")
		(29 "B.CrtYd" user "Package Geometry/Place Bound Bottom")
		(35 "F.Fab" user "Ref Des/Assembly Top")
		(33 "B.Fab" user "Ref Des/Assembly Bottom")
	)
	(footprint ""
		(layer "F.Cu")
		(at 182.964582 -426.8216 180)
		(property "Reference" "R2950"
			(at 0 0 180)
			(layer "F.SilkS")
			(hide yes)
			(effects
				(font
					(size 1.27 1.27)
				)
			)
		)
		(property "Value" ""
			(at 0 0 180)
			(layer "F.Fab")
			(effects
				(font
					(size 1.27 1.27)
				)
			)
		)
		(duplicate_pad_numbers_are_jumpers no)
		(fp_line
			(start 0.7874 0.4064)
			(end -0.7874 0.4064)
			(stroke
				(width 0.1524)
				(type default)
			)
			(layer "F.SilkS")
		)
		(fp_line
			(start 0.7874 -0.4064)
			(end 0.7874 0.4064)
			(stroke
				(width 0.1524)
				(type default)
			)
			(layer "F.SilkS")
		)
		(fp_line
			(start -0.7874 0.4064)
			(end -0.7874 -0.4064)
			(stroke
				(width 0.1524)
				(type default)
			)
			(layer "F.SilkS")
		)
		(fp_line
			(start -0.7874 -0.4064)
			(end 0.7874 -0.4064)
			(stroke
				(width 0.1524)
				(type default)
			)
			(layer "F.SilkS")
		)
		(fp_line
			(start 0.67945 0.3048)
			(end 0.120396 0.3048)
			(stroke
				(width 0.1)
				(type default)
			)
			(layer "F.Fab")
		)
		(fp_line
			(start 0.67945 -0.3048)
			(end 0.67945 0.3048)
			(stroke
				(width 0.1)
				(type default)
			)
			(layer "F.Fab")
		)
		(fp_line
			(start 0.12065 -0.2794)
			(end 0.12065 -0.3048)
			(stroke
				(width 0.1)
				(type default)
			)
			(layer "F.Fab")
		)
		(fp_line
			(start 0.12065 -0.3048)
			(end 0.67945 -0.3048)
			(stroke
				(width 0.1)
				(type default)
			)
			(layer "F.Fab")
		)
		(fp_line
			(start 0.120396 0.3048)
			(end 0.120396 0.2794)
			(stroke
				(width 0.1)
				(type default)
			)
			(layer "F.Fab")
		)
		(fp_line
			(start 0.120396 0.2794)
			(end -0.12065 0.2794)
			(stroke
				(width 0.1)
				(type default)
			)
			(layer "F.Fab")
		)
		(fp_line
			(start -0.12065 0.3048)
			(end -0.67945 0.3048)
			(stroke
				(width 0.1)
				(type default)
			)
			(layer "F.Fab")
		)
		(fp_line
			(start -0.12065 0.2794)
			(end -0.12065 0.3048)
			(stroke
				(width 0.1)
				(type default)
			)
			(layer "F.Fab")
		)
		(fp_line
			(start -0.12065 -0.2794)
			(end 0.12065 -0.2794)
			(stroke
				(width 0.1)
				(type default)
			)
			(layer "F.Fab")
		)
		(fp_line
			(start -0.12065 -0.305054)
			(end -0.12065 -0.2794)
			(stroke
				(width 0.1)
				(type default)
			)
			(layer "F.Fab")
		)
		(fp_line
			(start -0.67945 0.3048)
			(end -0.67945 -0.305054)
			(stroke
				(width 0.1)
				(type default)
			)
			(layer "F.Fab")
		)
		(fp_line
			(start -0.67945 -0.305054)
			(end -0.12065 -0.305054)
			(stroke
				(width 0.1)
				(type default)
			)
			(layer "F.Fab")
		)
		(pad "1" smd circle
			(at -0.40005 0 180)
			(size 0 0)
			(layers "F.Cu" "F.Mask" "F.Paste")
			(net "P3V3_AUX")
		)
		(pad "2" smd circle
			(at 0.40005 0 180)
			(size 0 0)
			(layers "F.Cu" "F.Mask" "F.Paste")
			(net "FM_PDB_BUF_EN_R")
		)
	)
	(footprint ""
		(layer "F.Cu")
		(at 160.83788 -121.376948 180)
		(property "Reference" "R1405"
			(at 0 0 180)
			(layer "F.SilkS")
			(hide yes)
			(effects
				(font
					(size 1.27 1.27)
				)
			)
		)
		(property "Value" ""
			(at 0 0 180)
			(layer "F.Fab")
			(effects
				(font
					(size 1.27 1.27)
				)
			)
		)
		(duplicate_pad_numbers_are_jumpers no)
		(fp_line
			(start 0.7874 0.4064)
			(end -0.7874 0.4064)
			(stroke
				(width 0.1524)
				(type default)
			)
			(layer "F.SilkS")
		)
		(fp_line
			(start 0.7874 -0.4064)
			(end 0.7874 0.4064)
			(stroke
				(width 0.1524)
				(type default)
			)
			(layer "F.SilkS")
		)
		(fp_line
			(start -0.7874 0.4064)
			(end -0.7874 -0.4064)
			(stroke
				(width 0.1524)
				(type default)
			)
			(layer "F.SilkS")
		)
		(fp_line
			(start -0.7874 -0.4064)
			(end 0.7874 -0.4064)
			(stroke
				(width 0.1524)
				(type default)
			)
			(layer "F.SilkS")
		)
		(fp_line
			(start 0.67945 0.3048)
			(end 0.120396 0.3048)
			(stroke
				(width 0.1)
				(type default)
			)
			(layer "F.Fab")
		)
		(fp_line
			(start 0.67945 -0.3048)
			(end 0.67945 0.3048)
			(stroke
				(width 0.1)
				(type default)
			)
			(layer "F.Fab")
		)
		(fp_line
			(start 0.12065 -0.2794)
			(end 0.12065 -0.3048)
			(stroke
				(width 0.1)
				(type default)
			)
			(layer "F.Fab")
		)
		(fp_line
			(start 0.12065 -0.3048)
			(end 0.67945 -0.3048)
			(stroke
				(width 0.1)
				(type default)
			)
			(layer "F.Fab")
		)
		(fp_line
			(start 0.120396 0.3048)
			(end 0.120396 0.2794)
			(stroke
				(width 0.1)
				(type default)
			)
			(layer "F.Fab")
		)
		(fp_line
			(start 0.120396 0.2794)
			(end -0.12065 0.2794)
			(stroke
				(width 0.1)
				(type default)
			)
			(layer "F.Fab")
		)
		(fp_line
			(start -0.12065 0.3048)
			(end -0.67945 0.3048)
			(stroke
				(width 0.1)
				(type default)
			)
			(layer "F.Fab")
		)
		(fp_line
			(start -0.12065 0.2794)
			(end -0.12065 0.3048)
			(stroke
				(width 0.1)
				(type default)
			)
			(layer "F.Fab")
		)
		(fp_line
			(start -0.12065 -0.2794)
			(end 0.12065 -0.2794)
			(stroke
				(width 0.1)
				(type default)
			)
			(layer "F.Fab")
		)
		(fp_line
			(start -0.12065 -0.305054)
			(end -0.12065 -0.2794)
			(stroke
				(width 0.1)
				(type default)
			)
			(layer "F.Fab")
		)
		(fp_line
			(start -0.67945 0.3048)
			(end -0.67945 -0.305054)
			(stroke
				(width 0.1)
				(type default)
			)
			(layer "F.Fab")
		)
		(fp_line
			(start -0.67945 -0.305054)
			(end -0.12065 -0.305054)
			(stroke
				(width 0.1)
				(type default)
			)
			(layer "F.Fab")
		)
		(pad "1" smd circle
			(at -0.40005 0 180)
			(size 0 0)
			(layers "F.Cu" "F.Mask" "F.Paste")
			(net "FM_PVCCIN_CPU0_R_EN")
		)
		(pad "2" smd circle
			(at 0.40005 0 180)
			(size 0 0)
			(layers "F.Cu" "F.Mask" "F.Paste")
			(net "GND")
		)
	)
)
